# T6G (Grand Teton) — schematic netlist excerpt (pin names and nets, part order shuffled) for the footprints in the layout excerpt that follows; sources: Cadence DE-HDL packaged netlist, KiCad conversion of 04192023_DAF0TMB3IC0_F0TG_MB_C_brd_V02_OCP.brd

C833  Q_CAP_DIFFBUS  DIFF BUS_0.22UF 6.3V 20% X6S  pkg C0201  page 65 : \1\ = P5E_CPU1_P0_TX_C_DP<2> ; \2\ = P5E_CPU1_P0_TX_DP<2>
H6000  HOLE  EMPTY  pkg TH  page 230 : \1\ = GND
R4069  Q_RES  4.7K 5% EMPTY  pkg 0402LF  page 134 : A = P3V3_OCP_EN_1_R ; B = GND
C1990  Q_CAP_DIFFBUS  DIFF BUS_0.22UF 6.3V 20% X6S  pkg C0201  page 67 : \1\ = P3E_CPU0_P4_TX_C_DN<3> ; \2\ = P3E_CPU0_P4_TX_DN<3>

(kicad_pcb
	(version 20260206)
	(generator "pcbnew")
	(generator_version "10.0")
	(general
		(thickness 1.6)
		(legacy_teardrops no)
	)
	(paper "A4")
	(title_block
		(title "04192023_DAF0TMB3IC0_F0TG_MB_C_brd_V02_OCP.brd")
		(comment 1 "Grand Teton / footprints 2362-2365 of 8354")
	)
	(layers
		(0 "F.Cu" signal "TOP")
		(4 "In1.Cu" signal "GND")
		(6 "In2.Cu" signal "IN1")
		(8 "In3.Cu" signal "GND1")
		(10 "In4.Cu" signal "IN2")
		(12 "In5.Cu" signal "GND2")
		(14 "In6.Cu" signal "IN3")
		(16 "In7.Cu" signal "GND3")
		(18 "In8.Cu" signal "VCC")
		(20 "In9.Cu" signal "VCC1")
		(22 "In10.Cu" signal "GND4")
		(24 "In11.Cu" signal "IN4")
		(26 "In12.Cu" signal "GND5")
		(28 "In13.Cu" signal "IN5")
		(30 "In14.Cu" signal "GND6")
		(32 "In15.Cu" signal "IN6")
		(34 "In16.Cu" signal "GND7")
		(2 "B.Cu" signal "BOTTOM")
		(9 "F.Adhes" user "F.Adhesive")
		(11 "B.Adhes" user "B.Adhesive")
		(13 "F.Paste" user "Package Geometry/Pastemask Top")
		(15 "B.Paste" user "Package Geometry/Pastemask Bottom")
		(5 "F.SilkS" user "Ref Des/Silkscreen Top")
		(7 "B.SilkS" user "Ref Des/Silkscreen Bottom")
		(1 "F.Mask" user "Board Geometry/Soldermask Top")
		(3 "B.Mask" user "Board Geometry/Soldermask Bottom")
		(17 "Dwgs.User" user "User.Drawings")
		(19 "Cmts.User" user "User.Comments")
		(21 "Eco1.User" user "User.Eco1")
		(23 "Eco2.User" user "User.Eco2")
		(25 "Edge.Cuts" user "Board Geometry/Outline")
		(27 "Margin" user)
		(31 "F.CrtYd" user "Package Geometry/Place Bound Top")
		(29 "B.CrtYd" user "Package Geometry/Place Bound Bottom")
		(35 "F.Fab" user "Ref Des/Assembly Top")
		(33 "B.Fab" user "Ref Des/Assembly Bottom")
	)
	(footprint ""
		(layer "F.Cu")
		(at 42.989754 -373.03583 -90)
		(property "Reference" "C833"
			(at 0 0 270)
			(layer "F.SilkS")
			(hide yes)
			(effects
				(font
					(size 1.27 1.27)
				)
			)
		)
		(property "Value" ""
			(at 0 0 270)
			(layer "F.Fab")
			(effects
				(font
					(size 1.27 1.27)
				)
			)
		)
		(duplicate_pad_numbers_are_jumpers no)
		(fp_line
			(start -0.299974 0.150114)
			(end -0.299974 -0.150114)
			(stroke
				(width 0.1)
				(type default)
			)
			(layer "F.Fab")
		)
		(fp_line
			(start 0.299974 0.150114)
			(end -0.299974 0.150114)
			(stroke
				(width 0.1)
				(type default)
			)
			(layer "F.Fab")
		)
		(fp_line
			(start -0.299974 -0.150114)
			(end 0.299974 -0.150114)
			(stroke
				(width 0.1)
				(type default)
			)
			(layer "F.Fab")
		)
		(fp_line
			(start 0.299974 -0.150114)
			(end 0.299974 0.150114)
			(stroke
				(width 0.1)
				(type default)
			)
			(layer "F.Fab")
		)
		(pad "1" smd rect
			(at -0.2667 0 270)
			(size 0.3048 0.381)
			(layers "F.Cu" "F.Mask" "F.Paste")
			(net "P5E_CPU1_P0_TX_C_DP<2>")
		)
		(pad "2" smd rect
			(at 0.2667 0 270)
			(size 0.3048 0.381)
			(layers "F.Cu" "F.Mask" "F.Paste")
			(net "P5E_CPU1_P0_TX_DP<2>")
		)
	)
	(footprint ""
		(layer "F.Cu")
		(at 239.152684 -57.41289)
		(property "Reference" "C1990"
			(at 0 0 0)
			(layer "F.SilkS")
			(hide yes)
			(effects
				(font
					(size 1.27 1.27)
				)
			)
		)
		(property "Value" ""
			(at 0 0 0)
			(layer "F.Fab")
			(effects
				(font
					(size 1.27 1.27)
				)
			)
		)
		(duplicate_pad_numbers_are_jumpers no)
		(fp_line
			(start -0.299974 -0.150114)
			(end 0.299974 -0.150114)
			(stroke
				(width 0.1)
				(type default)
			)
			(layer "F.Fab")
		)
		(fp_line
			(start -0.299974 0.150114)
			(end -0.299974 -0.150114)
			(stroke
				(width 0.1)
				(type default)
			)
			(layer "F.Fab")
		)
		(fp_line
			(start 0.299974 -0.150114)
			(end 0.299974 0.150114)
			(stroke
				(width 0.1)
				(type default)
			)
			(layer "F.Fab")
		)
		(fp_line
			(start 0.299974 0.150114)
			(end -0.299974 0.150114)
			(stroke
				(width 0.1)
				(type default)
			)
			(layer "F.Fab")
		)
		(pad "1" smd rect
			(at -0.2667 0)
			(size 0.3048 0.381)
			(layers "F.Cu" "F.Mask" "F.Paste")
			(net "P3E_CPU0_P4_TX_C_DN<3>")
		)
		(pad "2" smd rect
			(at 0.2667 0)
			(size 0.3048 0.381)
			(layers "F.Cu" "F.Mask" "F.Paste")
			(net "P3E_CPU0_P4_TX_DN<3>")
		)
	)
	(footprint ""
		(layer "F.Cu")
		(at 455.01306 -41.105836 180)
		(property "Reference" "R4069"
			(at 0 0 180)
			(layer "F.SilkS")
			(hide yes)
			(effects
				(font
					(size 1.27 1.27)
				)
			)
		)
		(property "Value" ""
			(at 0 0 180)
			(layer "F.Fab")
			(effects
				(font
					(size 1.27 1.27)
				)
			)
		)
		(duplicate_pad_numbers_are_jumpers no)
		(fp_line
			(start 0.7874 0.4064)
			(end -0.7874 0.4064)
			(stroke
				(width 0.1524)
				(type default)
			)
			(layer "F.SilkS")
		)
		(fp_line
			(start 0.7874 -0.4064)
			(end 0.7874 0.4064)
			(stroke
				(width 0.1524)
				(type default)
			)
			(layer "F.SilkS")
		)
		(fp_line
			(start -0.7874 0.4064)
			(end -0.7874 -0.4064)
			(stroke
				(width 0.1524)
				(type default)
			)
			(layer "F.SilkS")
		)
		(fp_line
			(start -0.7874 -0.4064)
			(end 0.7874 -0.4064)
			(stroke
				(width 0.1524)
				(type default)
			)
			(layer "F.SilkS")
		)
		(fp_line
			(start 0.67945 0.3048)
			(end 0.120396 0.3048)
			(stroke
				(width 0.1)
				(type default)
			)
			(layer "F.Fab")
		)
		(fp_line
			(start 0.67945 -0.3048)
			(end 0.67945 0.3048)
			(stroke
				(width 0.1)
				(type default)
			)
			(layer "F.Fab")
		)
		(fp_line
			(start 0.12065 -0.2794)
			(end 0.12065 -0.3048)
			(stroke
				(width 0.1)
				(type default)
			)
			(layer "F.Fab")
		)
		(fp_line
			(start 0.12065 -0.3048)
			(end 0.67945 -0.3048)
			(stroke
				(width 0.1)
				(type default)
			)
			(layer "F.Fab")
		)
		(fp_line
			(start 0.120396 0.3048)
			(end 0.120396 0.2794)
			(stroke
				(width 0.1)
				(type default)
			)
			(layer "F.Fab")
		)
		(fp_line
			(start 0.120396 0.2794)
			(end -0.12065 0.2794)
			(stroke
				(width 0.1)
				(type default)
			)
			(layer "F.Fab")
		)
		(fp_line
			(start -0.12065 0.3048)
			(end -0.67945 0.3048)
			(stroke
				(width 0.1)
				(type default)
			)
			(layer "F.Fab")
		)
		(fp_line
			(start -0.12065 0.2794)
			(end -0.12065 0.3048)
			(stroke
				(width 0.1)
				(type default)
			)
			(layer "F.Fab")
		)
		(fp_line
			(start -0.12065 -0.2794)
			(end 0.12065 -0.2794)
			(stroke
				(width 0.1)
				(type default)
			)
			(layer "F.Fab")
		)
		(fp_line
			(start -0.12065 -0.305054)
			(end -0.12065 -0.2794)
			(stroke
				(width 0.1)
				(type default)
			)
			(layer "F.Fab")
		)
		(fp_line
			(start -0.67945 0.3048)
			(end -0.67945 -0.305054)
			(stroke
				(width 0.1)
				(type default)
			)
			(layer "F.Fab")
		)
		(fp_line
			(start -0.67945 -0.305054)
			(end -0.12065 -0.305054)
			(stroke
				(width 0.1)
				(type default)
			)
			(layer "F.Fab")
		)
		(pad "1" smd circle
			(at -0.40005 0 180)
			(size 0 0)
			(layers "F.Cu" "F.Mask" "F.Paste")
			(net "P3V3_OCP_EN_1_R")
		)
		(pad "2" smd circle
			(at 0.40005 0 180)
			(size 0 0)
			(layers "F.Cu" "F.Mask" "F.Paste")
			(net "GND")
		)
	)
	(footprint ""
		(layer "F.Cu")
		(at 447.44005 -40.420036)
		(property "Reference" "H6000"
			(at -2.5146 -3.58013 0)
			(unlocked yes)
			(layer "F.SilkS")
			(effects
				(font
					(size 0.7874 0.5842)
					(thickness 0.1524)
				)
				(justify left)
			)
		)
		(property "Value" ""
			(at 0 0 0)
			(layer "F.Fab")
			(effects
				(font
					(size 1.27 1.27)
				)
			)
		)
		(duplicate_pad_numbers_are_jumpers no)
		(pad "1" thru_hole circle
			(at 0 0)
			(size 6.1976 6.1976)
			(drill 3.7338)
			(layers "*.Cu" "*.Mask")
			(remove_unused_layers no)
			(net "GND")
			(clearance -0.9779)
			(padstack
				(mode front_inner_back)
				(layer "Inner"
					(shape circle)
					(size 5.5372 5.5372)
					(clearance -0.6477)
				)
				(layer "B.Cu"
					(shape circle)
					(size 6.1976 6.1976)
					(clearance -0.9779)
				)
			)
		)
	)
)
